(kicad_pcb
	(version 20260206)
	(generator "pcbnew")
	(generator_version "10.0")
	(general
		(thickness 1.6)
		(legacy_teardrops no)
	)
	(paper "A4")
	(title_block
		(title "04192023_DAF0TMB3IC0_F0TG_MB_C_brd_V02_OCP.brd")
		(comment 1 "Grand Teton / footprint 4641 of 8354 (U6012), pads 112-223 of 354")
	)
	(layers
		(0 "F.Cu" signal "TOP")
		(4 "In1.Cu" signal "GND")
		(6 "In2.Cu" signal "IN1")
		(8 "In3.Cu" signal "GND1")
		(10 "In4.Cu" signal "IN2")
		(12 "In5.Cu" signal "GND2")
		(14 "In6.Cu" signal "IN3")
		(16 "In7.Cu" signal "GND3")
		(18 "In8.Cu" signal "VCC")
		(20 "In9.Cu" signal "VCC1")
		(22 "In10.Cu" signal "GND4")
		(24 "In11.Cu" signal "IN4")
		(26 "In12.Cu" signal "GND5")
		(28 "In13.Cu" signal "IN5")
		(30 "In14.Cu" signal "GND6")
		(32 "In15.Cu" signal "IN6")
		(34 "In16.Cu" signal "GND7")
		(2 "B.Cu" signal "BOTTOM")
		(9 "F.Adhes" user "F.Adhesive")
		(11 "B.Adhes" user "B.Adhesive")
		(13 "F.Paste" user "Package Geometry/Pastemask Top")
		(15 "B.Paste" user "Package Geometry/Pastemask Bottom")
		(5 "F.SilkS" user "Ref Des/Silkscreen Top")
		(7 "B.SilkS" user "Ref Des/Silkscreen Bottom")
		(1 "F.Mask" user "Board Geometry/Soldermask Top")
		(3 "B.Mask" user "Board Geometry/Soldermask Bottom")
		(17 "Dwgs.User" user "User.Drawings")
		(19 "Cmts.User" user "User.Comments")
		(21 "Eco1.User" user "User.Eco1")
		(23 "Eco2.User" user "User.Eco2")
		(25 "Edge.Cuts" user "Board Geometry/Outline")
		(27 "Margin" user)
		(31 "F.CrtYd" user "Package Geometry/Place Bound Top")
		(29 "B.CrtYd" user "Package Geometry/Place Bound Bottom")
		(35 "F.Fab" user "Ref Des/Assembly Top")
		(33 "B.Fab" user "Ref Des/Assembly Bottom")
	)
	(footprint ""
		(layer "F.Cu")
		(at 412.095696 -395.724634)
		(property "Reference" "U6012"
			(at -8.00862 -7.649972 0)
			(unlocked yes)
			(layer "F.SilkS")
			(effects
				(font
					(size 0.7874 0.5842)
					(thickness 0.1524)
				)
				(justify left)
			)
		)
		(property "Value" ""
			(at 0 0 0)
			(layer "F.Fab")
			(effects
				(font
					(size 1.27 1.27)
				)
			)
		)
		(duplicate_pad_numbers_are_jumpers no)
		(pad "BV32" smd circle
			(at 1.20269 2.724912)
			(size 0.381 0.381)
			(layers "F.Cu" "F.Mask" "F.Paste")
			(net "GND")
		)
		(pad "BW2" smd circle
			(at 1.150112 -3.41884)
			(size 0.3048 0.3048)
			(layers "F.Cu" "F.Mask" "F.Paste")
			(net "GND")
		)
		(pad "BW34" smd circle
			(at 1.150112 3.420364)
			(size 0.3048 0.3048)
			(layers "F.Cu" "F.Mask" "F.Paste")
			(net "GND")
		)
		(pad "BY1" smd oval
			(at 0.849884 -3.938524)
			(size 0.254 0.3302)
			(layers "F.Cu" "F.Mask" "F.Paste")
			(net "GND")
		)
		(pad "BY35" smd oval
			(at 0.849884 3.940048)
			(size 0.254 0.3302)
			(layers "F.Cu" "F.Mask" "F.Paste")
			(net "GND")
		)
		(pad "C2" smd circle
			(at 10.750042 -3.41884)
			(size 0.3048 0.3048)
			(layers "F.Cu" "F.Mask" "F.Paste")
			(net "NCF_CPU0_P2_GND")
		)
		(pad "C34" smd circle
			(at 10.750042 3.420364)
			(size 0.3048 0.3048)
			(layers "F.Cu" "F.Mask" "F.Paste")
			(net "NCF_CPU0_P2_GND")
		)
		(pad "CA7" smd circle
			(at 0.80264 -2.12471)
			(size 0.381 0.381)
			(layers "F.Cu" "F.Mask" "F.Paste")
			(net "P5E_CPU0_P2_TX_BUF_DP<8>")
		)
		(pad "CA26" smd circle
			(at 0.80264 1.339342)
			(size 0.381 0.381)
			(layers "F.Cu" "F.Mask" "F.Paste")
			(net "P5E_CPU0_P2_RX_DP<8>")
		)
		(pad "CB2" smd circle
			(at 0.54991 -3.41884)
			(size 0.3048 0.3048)
			(layers "F.Cu" "F.Mask" "F.Paste")
			(net "P5E_CPU0_P2_RX_BUF_DN<8>")
		)
		(pad "CB34" smd circle
			(at 0.54991 3.420364)
			(size 0.3048 0.3048)
			(layers "F.Cu" "F.Mask" "F.Paste")
			(net "P5E_CPU0_P2_TX_C_DN<8>")
		)
		(pad "CC10" smd circle
			(at 0.40259 -1.431798)
			(size 0.381 0.381)
			(layers "F.Cu" "F.Mask" "F.Paste")
			(net "P5E_CPU0_P2_TX_BUF_DN<8>")
		)
		(pad "CC29" smd circle
			(at 0.40259 2.032254)
			(size 0.381 0.381)
			(layers "F.Cu" "F.Mask" "F.Paste")
			(net "P5E_CPU0_P2_RX_DN<8>")
		)
		(pad "CD1" smd oval
			(at 0.249936 -3.938524)
			(size 0.254 0.3302)
			(layers "F.Cu" "F.Mask" "F.Paste")
			(net "P5E_CPU0_P2_RX_BUF_DP<8>")
		)
		(pad "CD35" smd oval
			(at 0.249936 3.940048)
			(size 0.254 0.3302)
			(layers "F.Cu" "F.Mask" "F.Paste")
			(net "P5E_CPU0_P2_TX_C_DP<8>")
		)
		(pad "CE4" smd circle
			(at 0.00254 -2.817368)
			(size 0.381 0.381)
			(layers "F.Cu" "F.Mask" "F.Paste")
			(net "GND")
		)
		(pad "CE13" smd circle
			(at 0.00254 -0.79629)
			(size 0.3048 0.3048)
			(layers "F.Cu" "F.Mask" "F.Paste")
			(net "GND")
		)
		(pad "CE17" smd circle
			(at 0.00254 -0.296164)
			(size 0.3048 0.3048)
			(layers "F.Cu" "F.Mask" "F.Paste")
			(net "P1V8_CPU0_RT2_1A")
		)
		(pad "CE20" smd circle
			(at 0.00254 0.203708)
			(size 0.3048 0.3048)
			(layers "F.Cu" "F.Mask" "F.Paste")
			(net "P1V8_CPU0_RT2_1A")
		)
		(pad "CE22" smd circle
			(at 0.00254 0.703834)
			(size 0.3048 0.3048)
			(layers "F.Cu" "F.Mask" "F.Paste")
			(net "GND")
		)
		(pad "CE32" smd circle
			(at 0.00254 2.724912)
			(size 0.381 0.381)
			(layers "F.Cu" "F.Mask" "F.Paste")
			(net "GND")
		)
		(pad "CF2" smd circle
			(at -0.050038 -3.41884)
			(size 0.3048 0.3048)
			(layers "F.Cu" "F.Mask" "F.Paste")
			(net "GND")
		)
		(pad "CF34" smd circle
			(at -0.050038 3.420364)
			(size 0.3048 0.3048)
			(layers "F.Cu" "F.Mask" "F.Paste")
			(net "GND")
		)
		(pad "CG1" smd oval
			(at -0.350012 -3.938524)
			(size 0.254 0.3302)
			(layers "F.Cu" "F.Mask" "F.Paste")
			(net "GND")
		)
		(pad "CG35" smd oval
			(at -0.350012 3.940048)
			(size 0.254 0.3302)
			(layers "F.Cu" "F.Mask" "F.Paste")
			(net "GND")
		)
		(pad "CH7" smd circle
			(at -0.39751 -2.12471)
			(size 0.381 0.381)
			(layers "F.Cu" "F.Mask" "F.Paste")
			(net "P5E_CPU0_P2_TX_BUF_DP<7>")
		)
		(pad "CH26" smd circle
			(at -0.39751 1.339342)
			(size 0.381 0.381)
			(layers "F.Cu" "F.Mask" "F.Paste")
			(net "P5E_CPU0_P2_RX_DP<7>")
		)
		(pad "CJ2" smd circle
			(at -0.649986 -3.41884)
			(size 0.3048 0.3048)
			(layers "F.Cu" "F.Mask" "F.Paste")
			(net "P5E_CPU0_P2_RX_BUF_DN<7>")
		)
		(pad "CJ34" smd circle
			(at -0.649986 3.420364)
			(size 0.3048 0.3048)
			(layers "F.Cu" "F.Mask" "F.Paste")
			(net "P5E_CPU0_P2_TX_C_DN<7>")
		)
		(pad "CK10" smd circle
			(at -0.797306 -1.431798)
			(size 0.381 0.381)
			(layers "F.Cu" "F.Mask" "F.Paste")
			(net "P5E_CPU0_P2_TX_BUF_DN<7>")
		)
		(pad "CK29" smd circle
			(at -0.797306 2.032254)
			(size 0.381 0.381)
			(layers "F.Cu" "F.Mask" "F.Paste")
			(net "P5E_CPU0_P2_RX_DN<7>")
		)
		(pad "CL1" smd oval
			(at -0.94996 -3.938524)
			(size 0.254 0.3302)
			(layers "F.Cu" "F.Mask" "F.Paste")
			(net "P5E_CPU0_P2_RX_BUF_DP<7>")
		)
		(pad "CL35" smd oval
			(at -0.94996 3.940048)
			(size 0.254 0.3302)
			(layers "F.Cu" "F.Mask" "F.Paste")
			(net "P5E_CPU0_P2_TX_C_DP<7>")
		)
		(pad "CM4" smd circle
			(at -1.197356 -2.817368)
			(size 0.381 0.381)
			(layers "F.Cu" "F.Mask" "F.Paste")
			(net "GND")
		)
		(pad "CM13" smd circle
			(at -1.197356 -0.79629)
			(size 0.3048 0.3048)
			(layers "F.Cu" "F.Mask" "F.Paste")
			(net "GND")
		)
		(pad "CM17" smd circle
			(at -1.197356 -0.296164)
			(size 0.3048 0.3048)
			(layers "F.Cu" "F.Mask" "F.Paste")
			(net "P1V8_CPU0_RT2_1A")
		)
		(pad "CM20" smd circle
			(at -1.197356 0.203708)
			(size 0.3048 0.3048)
			(layers "F.Cu" "F.Mask" "F.Paste")
			(net "P1V8_CPU0_RT2_1A")
		)
		(pad "CM22" smd circle
			(at -1.197356 0.703834)
			(size 0.3048 0.3048)
			(layers "F.Cu" "F.Mask" "F.Paste")
			(net "GND")
		)
		(pad "CM32" smd circle
			(at -1.197356 2.724912)
			(size 0.381 0.381)
			(layers "F.Cu" "F.Mask" "F.Paste")
			(net "GND")
		)
		(pad "CN2" smd circle
			(at -1.249934 -3.41884)
			(size 0.3048 0.3048)
			(layers "F.Cu" "F.Mask" "F.Paste")
			(net "GND")
		)
		(pad "CN34" smd circle
			(at -1.249934 3.420364)
			(size 0.3048 0.3048)
			(layers "F.Cu" "F.Mask" "F.Paste")
			(net "GND")
		)
		(pad "CP1" smd oval
			(at -1.549908 -3.938524)
			(size 0.254 0.3302)
			(layers "F.Cu" "F.Mask" "F.Paste")
			(net "GND")
		)
		(pad "CP35" smd oval
			(at -1.549908 3.940048)
			(size 0.254 0.3302)
			(layers "F.Cu" "F.Mask" "F.Paste")
			(net "GND")
		)
		(pad "CR7" smd circle
			(at -1.597406 -2.12471)
			(size 0.381 0.381)
			(layers "F.Cu" "F.Mask" "F.Paste")
			(net "P5E_CPU0_P2_TX_BUF_DP<6>")
		)
		(pad "CR26" smd circle
			(at -1.597406 1.339342)
			(size 0.381 0.381)
			(layers "F.Cu" "F.Mask" "F.Paste")
			(net "P5E_CPU0_P2_RX_DP<6>")
		)
		(pad "CT2" smd circle
			(at -1.849882 -3.41884)
			(size 0.3048 0.3048)
			(layers "F.Cu" "F.Mask" "F.Paste")
			(net "P5E_CPU0_P2_RX_BUF_DN<6>")
		)
		(pad "CT34" smd circle
			(at -1.849882 3.420364)
			(size 0.3048 0.3048)
			(layers "F.Cu" "F.Mask" "F.Paste")
			(net "P5E_CPU0_P2_TX_C_DN<6>")
		)
		(pad "CU10" smd circle
			(at -1.997456 -1.431798)
			(size 0.381 0.381)
			(layers "F.Cu" "F.Mask" "F.Paste")
			(net "P5E_CPU0_P2_TX_BUF_DN<6>")
		)
		(pad "CU29" smd circle
			(at -1.997456 2.032254)
			(size 0.381 0.381)
			(layers "F.Cu" "F.Mask" "F.Paste")
			(net "P5E_CPU0_P2_RX_DN<6>")
		)
		(pad "CV1" smd oval
			(at -2.15011 -3.938524)
			(size 0.254 0.3302)
			(layers "F.Cu" "F.Mask" "F.Paste")
			(net "P5E_CPU0_P2_RX_BUF_DP<6>")
		)
		(pad "CV35" smd oval
			(at -2.15011 3.940048)
			(size 0.254 0.3302)
			(layers "F.Cu" "F.Mask" "F.Paste")
			(net "P5E_CPU0_P2_TX_C_DP<6>")
		)
		(pad "CW4" smd circle
			(at -2.397506 -2.817368)
			(size 0.381 0.381)
			(layers "F.Cu" "F.Mask" "F.Paste")
			(net "GND")
		)
		(pad "CW13" smd circle
			(at -2.397506 -0.79629)
			(size 0.3048 0.3048)
			(layers "F.Cu" "F.Mask" "F.Paste")
			(net "GND")
		)
		(pad "CW17" smd circle
			(at -2.397506 -0.296164)
			(size 0.3048 0.3048)
			(layers "F.Cu" "F.Mask" "F.Paste")
			(net "P0V9_CPU0_RT_2D")
		)
		(pad "CW20" smd circle
			(at -2.397506 0.203708)
			(size 0.3048 0.3048)
			(layers "F.Cu" "F.Mask" "F.Paste")
			(net "P0V9_CPU0_RT_2D")
		)
		(pad "CW22" smd circle
			(at -2.397506 0.703834)
			(size 0.3048 0.3048)
			(layers "F.Cu" "F.Mask" "F.Paste")
			(net "GND")
		)
		(pad "CW32" smd circle
			(at -2.397506 2.724912)
			(size 0.381 0.381)
			(layers "F.Cu" "F.Mask" "F.Paste")
			(net "GND")
		)
		(pad "CY2" smd circle
			(at -2.450084 -3.41884)
			(size 0.3048 0.3048)
			(layers "F.Cu" "F.Mask" "F.Paste")
			(net "GND")
		)
		(pad "CY34" smd circle
			(at -2.450084 3.420364)
			(size 0.3048 0.3048)
			(layers "F.Cu" "F.Mask" "F.Paste")
			(net "GND")
		)
		(pad "D1" smd oval
			(at 10.450068 -3.938524)
			(size 0.254 0.3302)
			(layers "F.Cu" "F.Mask" "F.Paste")
			(net "NCF_CPU0_P2_GND")
		)
		(pad "D35" smd oval
			(at 10.450068 3.940048)
			(size 0.254 0.3302)
			(layers "F.Cu" "F.Mask" "F.Paste")
			(net "NCF_CPU0_P2_GND")
		)
		(pad "DA1" smd oval
			(at -2.750058 -3.938524)
			(size 0.254 0.3302)
			(layers "F.Cu" "F.Mask" "F.Paste")
			(net "GND")
		)
		(pad "DA35" smd oval
			(at -2.750058 3.940048)
			(size 0.254 0.3302)
			(layers "F.Cu" "F.Mask" "F.Paste")
			(net "GND")
		)
		(pad "DB7" smd circle
			(at -2.797302 -2.12471)
			(size 0.381 0.381)
			(layers "F.Cu" "F.Mask" "F.Paste")
			(net "P5E_CPU0_P2_TX_BUF_DP<5>")
		)
		(pad "DB26" smd circle
			(at -2.797302 1.339342)
			(size 0.381 0.381)
			(layers "F.Cu" "F.Mask" "F.Paste")
			(net "P5E_CPU0_P2_RX_DP<5>")
		)
		(pad "DC2" smd circle
			(at -3.050032 -3.41884)
			(size 0.3048 0.3048)
			(layers "F.Cu" "F.Mask" "F.Paste")
			(net "P5E_CPU0_P2_RX_BUF_DN<5>")
		)
		(pad "DC34" smd circle
			(at -3.050032 3.420364)
			(size 0.3048 0.3048)
			(layers "F.Cu" "F.Mask" "F.Paste")
			(net "P5E_CPU0_P2_TX_C_DN<5>")
		)
		(pad "DD10" smd circle
			(at -3.197352 -1.431798)
			(size 0.381 0.381)
			(layers "F.Cu" "F.Mask" "F.Paste")
			(net "P5E_CPU0_P2_TX_BUF_DN<5>")
		)
		(pad "DD29" smd circle
			(at -3.197352 2.032254)
			(size 0.381 0.381)
			(layers "F.Cu" "F.Mask" "F.Paste")
			(net "P5E_CPU0_P2_RX_DN<5>")
		)
		(pad "DE1" smd oval
			(at -3.350006 -3.938524)
			(size 0.254 0.3302)
			(layers "F.Cu" "F.Mask" "F.Paste")
			(net "P5E_CPU0_P2_RX_BUF_DP<5>")
		)
		(pad "DE35" smd oval
			(at -3.350006 3.940048)
			(size 0.254 0.3302)
			(layers "F.Cu" "F.Mask" "F.Paste")
			(net "P5E_CPU0_P2_TX_C_DP<5>")
		)
		(pad "DF4" smd circle
			(at -3.597402 -2.817368)
			(size 0.381 0.381)
			(layers "F.Cu" "F.Mask" "F.Paste")
			(net "GND")
		)
		(pad "DF13" smd circle
			(at -3.597402 -0.79629)
			(size 0.3048 0.3048)
			(layers "F.Cu" "F.Mask" "F.Paste")
			(net "GND")
		)
		(pad "DF17" smd circle
			(at -3.597402 -0.296164)
			(size 0.3048 0.3048)
			(layers "F.Cu" "F.Mask" "F.Paste")
			(net "P0V9_CPU0_RT2_2A_2D")
		)
		(pad "DF20" smd circle
			(at -3.597402 0.203708)
			(size 0.3048 0.3048)
			(layers "F.Cu" "F.Mask" "F.Paste")
			(net "P0V9_CPU0_RT2_2A_2D")
		)
		(pad "DF22" smd circle
			(at -3.597402 0.703834)
			(size 0.3048 0.3048)
			(layers "F.Cu" "F.Mask" "F.Paste")
			(net "GND")
		)
		(pad "DF32" smd circle
			(at -3.597402 2.724912)
			(size 0.381 0.381)
			(layers "F.Cu" "F.Mask" "F.Paste")
			(net "GND")
		)
		(pad "DG2" smd circle
			(at -3.64998 -3.41884)
			(size 0.3048 0.3048)
			(layers "F.Cu" "F.Mask" "F.Paste")
			(net "GND")
		)
		(pad "DG34" smd circle
			(at -3.64998 3.420364)
			(size 0.3048 0.3048)
			(layers "F.Cu" "F.Mask" "F.Paste")
			(net "GND")
		)
		(pad "DH1" smd oval
			(at -3.949954 -3.938524)
			(size 0.254 0.3302)
			(layers "F.Cu" "F.Mask" "F.Paste")
			(net "GND")
		)
		(pad "DH35" smd oval
			(at -3.949954 3.940048)
			(size 0.254 0.3302)
			(layers "F.Cu" "F.Mask" "F.Paste")
			(net "GND")
		)
		(pad "DJ7" smd circle
			(at -3.997452 -2.12471)
			(size 0.381 0.381)
			(layers "F.Cu" "F.Mask" "F.Paste")
			(net "P5E_CPU0_P2_TX_BUF_DP<4>")
		)
		(pad "DJ26" smd circle
			(at -3.997452 1.339342)
			(size 0.381 0.381)
			(layers "F.Cu" "F.Mask" "F.Paste")
			(net "P5E_CPU0_P2_RX_DP<4>")
		)
		(pad "DK2" smd circle
			(at -4.249928 -3.41884)
			(size 0.3048 0.3048)
			(layers "F.Cu" "F.Mask" "F.Paste")
			(net "P5E_CPU0_P2_RX_BUF_DN<4>")
		)
		(pad "DK34" smd circle
			(at -4.249928 3.420364)
			(size 0.3048 0.3048)
			(layers "F.Cu" "F.Mask" "F.Paste")
			(net "P5E_CPU0_P2_TX_C_DN<4>")
		)
		(pad "DL10" smd circle
			(at -4.397502 -1.431798)
			(size 0.381 0.381)
			(layers "F.Cu" "F.Mask" "F.Paste")
			(net "P5E_CPU0_P2_TX_BUF_DN<4>")
		)
		(pad "DL29" smd circle
			(at -4.397502 2.032254)
			(size 0.381 0.381)
			(layers "F.Cu" "F.Mask" "F.Paste")
			(net "P5E_CPU0_P2_RX_DN<4>")
		)
		(pad "DM1" smd oval
			(at -4.549902 -3.938524)
			(size 0.254 0.3302)
			(layers "F.Cu" "F.Mask" "F.Paste")
			(net "P5E_CPU0_P2_RX_BUF_DP<4>")
		)
		(pad "DM35" smd oval
			(at -4.549902 3.940048)
			(size 0.254 0.3302)
			(layers "F.Cu" "F.Mask" "F.Paste")
			(net "P5E_CPU0_P2_TX_C_DP<4>")
		)
		(pad "DN4" smd circle
			(at -4.797298 -2.817368)
			(size 0.381 0.381)
			(layers "F.Cu" "F.Mask" "F.Paste")
			(net "GND")
		)
		(pad "DN13" smd circle
			(at -4.797298 -0.79629)
			(size 0.3048 0.3048)
			(layers "F.Cu" "F.Mask" "F.Paste")
			(net "GND")
		)
		(pad "DN17" smd circle
			(at -4.797298 -0.296164)
			(size 0.3048 0.3048)
			(layers "F.Cu" "F.Mask" "F.Paste")
			(net "P0V9_CPU0_RT2_2A")
		)
		(pad "DN20" smd circle
			(at -4.797298 0.203708)
			(size 0.3048 0.3048)
			(layers "F.Cu" "F.Mask" "F.Paste")
			(net "P0V9_CPU0_RT2_2A")
		)
		(pad "DN22" smd circle
			(at -4.797298 0.703834)
			(size 0.3048 0.3048)
			(layers "F.Cu" "F.Mask" "F.Paste")
			(net "GND")
		)
		(pad "DN32" smd circle
			(at -4.797298 2.724912)
			(size 0.381 0.381)
			(layers "F.Cu" "F.Mask" "F.Paste")
			(net "GND")
		)
		(pad "DP2" smd circle
			(at -4.849876 -3.41884)
			(size 0.3048 0.3048)
			(layers "F.Cu" "F.Mask" "F.Paste")
			(net "GND")
		)
		(pad "DP34" smd circle
			(at -4.849876 3.420364)
			(size 0.3048 0.3048)
			(layers "F.Cu" "F.Mask" "F.Paste")
			(net "GND")
		)
		(pad "DR1" smd oval
			(at -5.150104 -3.938524)
			(size 0.254 0.3302)
			(layers "F.Cu" "F.Mask" "F.Paste")
			(net "GND")
		)
		(pad "DR35" smd oval
			(at -5.150104 3.940048)
			(size 0.254 0.3302)
			(layers "F.Cu" "F.Mask" "F.Paste")
			(net "GND")
		)
		(pad "DT7" smd circle
			(at -5.197348 -2.12471)
			(size 0.381 0.381)
			(layers "F.Cu" "F.Mask" "F.Paste")
			(net "P5E_CPU0_P2_TX_BUF_DP<3>")
		)
		(pad "DT26" smd circle
			(at -5.197348 1.339342)
			(size 0.381 0.381)
			(layers "F.Cu" "F.Mask" "F.Paste")
			(net "P5E_CPU0_P2_RX_DP<3>")
		)
		(pad "DU2" smd circle
			(at -5.450078 -3.41884)
			(size 0.3048 0.3048)
			(layers "F.Cu" "F.Mask" "F.Paste")
			(net "P5E_CPU0_P2_RX_BUF_DN<3>")
		)
		(pad "DU34" smd circle
			(at -5.450078 3.420364)
			(size 0.3048 0.3048)
			(layers "F.Cu" "F.Mask" "F.Paste")
			(net "P5E_CPU0_P2_TX_C_DN<3>")
		)
		(pad "DV10" smd circle
			(at -5.597398 -1.431798)
			(size 0.381 0.381)
			(layers "F.Cu" "F.Mask" "F.Paste")
			(net "P5E_CPU0_P2_TX_BUF_DN<3>")
		)
		(pad "DV29" smd circle
			(at -5.597398 2.032254)
			(size 0.381 0.381)
			(layers "F.Cu" "F.Mask" "F.Paste")
			(net "P5E_CPU0_P2_RX_DN<3>")
		)
		(pad "DW1" smd oval
			(at -5.750052 -3.938524)
			(size 0.254 0.3302)
			(layers "F.Cu" "F.Mask" "F.Paste")
			(net "P5E_CPU0_P2_RX_BUF_DP<3>")
		)
		(pad "DW35" smd oval
			(at -5.750052 3.940048)
			(size 0.254 0.3302)
			(layers "F.Cu" "F.Mask" "F.Paste")
			(net "P5E_CPU0_P2_TX_C_DP<3>")
		)
		(pad "DY4" smd circle
			(at -5.997448 -2.817368)
			(size 0.381 0.381)
			(layers "F.Cu" "F.Mask" "F.Paste")
			(net "GND")
		)
		(pad "DY13" smd circle
			(at -5.997448 -0.79629)
			(size 0.3048 0.3048)
			(layers "F.Cu" "F.Mask" "F.Paste")
			(net "GND")
		)
		(pad "DY17" smd circle
			(at -5.997448 -0.296164)
			(size 0.3048 0.3048)
			(layers "F.Cu" "F.Mask" "F.Paste")
			(net "P0V9_CPU0_RT2_2A")
		)
		(pad "DY20" smd circle
			(at -5.997448 0.203708)
			(size 0.3048 0.3048)
			(layers "F.Cu" "F.Mask" "F.Paste")
			(net "P0V9_CPU0_RT2_2A")
		)
		(pad "DY22" smd circle
			(at -5.997448 0.703834)
			(size 0.3048 0.3048)
			(layers "F.Cu" "F.Mask" "F.Paste")
			(net "GND")
		)
	)
)
